# T6G (Grand Teton) — schematic netlist excerpt (pin names and nets, part order shuffled) for the footprints in the layout excerpt that follows; sources: Cadence DE-HDL packaged netlist, KiCad conversion of 04192023_DAF0TMB3IC0_F0TG_MB_C_brd_V02_OCP.brd

C6663  Q_CAP_DIFFBUS  DIFF BUS_0.22UF 6.3V 20% X6S  pkg C0201  page 330 : \1\ = P5E_CPU1_P1_TX_BUF_C_DP<1> ; \2\ = P5E_CPU1_P1_TX_BUF_DP<1>
R8235  Q_RES  0 5% CHIP  pkg 0402LF  page 217 : A = FM_PVDDCR_CPU1_P1_EN ; B = PVDDCR_CPU1_P1_EN_R
R1438  Q_RES  4.7K 5% EMPTY  pkg 0201LF  page 276 : A = P1V8_CPU0_RT_1D ; B = JTAG_TDI_RT_CPU0_P0

(kicad_pcb
	(version 20260206)
	(generator "pcbnew")
	(generator_version "10.0")
	(general
		(thickness 1.6)
		(legacy_teardrops no)
	)
	(paper "A4")
	(title_block
		(title "04192023_DAF0TMB3IC0_F0TG_MB_C_brd_V02_OCP.brd")
		(comment 1 "Grand Teton / footprints 7438-7440 of 8354")
	)
	(layers
		(0 "F.Cu" signal "TOP")
		(4 "In1.Cu" signal "GND")
		(6 "In2.Cu" signal "IN1")
		(8 "In3.Cu" signal "GND1")
		(10 "In4.Cu" signal "IN2")
		(12 "In5.Cu" signal "GND2")
		(14 "In6.Cu" signal "IN3")
		(16 "In7.Cu" signal "GND3")
		(18 "In8.Cu" signal "VCC")
		(20 "In9.Cu" signal "VCC1")
		(22 "In10.Cu" signal "GND4")
		(24 "In11.Cu" signal "IN4")
		(26 "In12.Cu" signal "GND5")
		(28 "In13.Cu" signal "IN5")
		(30 "In14.Cu" signal "GND6")
		(32 "In15.Cu" signal "IN6")
		(34 "In16.Cu" signal "GND7")
		(2 "B.Cu" signal "BOTTOM")
		(9 "F.Adhes" user "F.Adhesive")
		(11 "B.Adhes" user "B.Adhesive")
		(13 "F.Paste" user "Package Geometry/Pastemask Top")
		(15 "B.Paste" user "Package Geometry/Pastemask Bottom")
		(5 "F.SilkS" user "Ref Des/Silkscreen Top")
		(7 "B.SilkS" user "Ref Des/Silkscreen Bottom")
		(1 "F.Mask" user "Board Geometry/Soldermask Top")
		(3 "B.Mask" user "Board Geometry/Soldermask Bottom")
		(17 "Dwgs.User" user "User.Drawings")
		(19 "Cmts.User" user "User.Comments")
		(21 "Eco1.User" user "User.Eco1")
		(23 "Eco2.User" user "User.Eco2")
		(25 "Edge.Cuts" user "Board Geometry/Outline")
		(27 "Margin" user)
		(31 "F.CrtYd" user "Package Geometry/Place Bound Top")
		(29 "B.CrtYd" user "Package Geometry/Place Bound Bottom")
		(35 "F.Fab" user "Ref Des/Assembly Top")
		(33 "B.Fab" user "Ref Des/Assembly Bottom")
	)
	(footprint ""
		(layer "B.Cu")
		(at 24.765 -364.617 180)
		(property "Reference" "R8235"
			(at 0 0 0)
			(layer "B.SilkS")
			(hide yes)
			(effects
				(font
					(size 1.27 1.27)
				)
				(justify mirror)
			)
		)
		(property "Value" ""
			(at 0 0 0)
			(layer "B.Fab")
			(effects
				(font
					(size 1.27 1.27)
				)
				(justify mirror)
			)
		)
		(duplicate_pad_numbers_are_jumpers no)
		(fp_line
			(start 0.7874 0.4064)
			(end 0.7874 -0.4064)
			(stroke
				(width 0.1524)
				(type default)
			)
			(layer "B.SilkS")
		)
		(fp_line
			(start 0.7874 -0.4064)
			(end -0.7874 -0.4064)
			(stroke
				(width 0.1524)
				(type default)
			)
			(layer "B.SilkS")
		)
		(fp_line
			(start -0.7874 0.4064)
			(end 0.7874 0.4064)
			(stroke
				(width 0.1524)
				(type default)
			)
			(layer "B.SilkS")
		)
		(fp_line
			(start -0.7874 -0.4064)
			(end -0.7874 0.4064)
			(stroke
				(width 0.1524)
				(type default)
			)
			(layer "B.SilkS")
		)
		(fp_line
			(start 0.67945 0.3048)
			(end 0.67945 -0.305054)
			(stroke
				(width 0.1)
				(type default)
			)
			(layer "B.Fab")
		)
		(fp_line
			(start 0.67945 -0.305054)
			(end 0.12065 -0.305054)
			(stroke
				(width 0.1)
				(type default)
			)
			(layer "B.Fab")
		)
		(fp_line
			(start 0.12065 0.3048)
			(end 0.67945 0.3048)
			(stroke
				(width 0.1)
				(type default)
			)
			(layer "B.Fab")
		)
		(fp_line
			(start 0.12065 0.2794)
			(end 0.12065 0.3048)
			(stroke
				(width 0.1)
				(type default)
			)
			(layer "B.Fab")
		)
		(fp_line
			(start 0.12065 -0.2794)
			(end -0.12065 -0.2794)
			(stroke
				(width 0.1)
				(type default)
			)
			(layer "B.Fab")
		)
		(fp_line
			(start 0.12065 -0.305054)
			(end 0.12065 -0.2794)
			(stroke
				(width 0.1)
				(type default)
			)
			(layer "B.Fab")
		)
		(fp_line
			(start -0.120396 0.3048)
			(end -0.120396 0.2794)
			(stroke
				(width 0.1)
				(type default)
			)
			(layer "B.Fab")
		)
		(fp_line
			(start -0.120396 0.2794)
			(end 0.12065 0.2794)
			(stroke
				(width 0.1)
				(type default)
			)
			(layer "B.Fab")
		)
		(fp_line
			(start -0.12065 -0.2794)
			(end -0.12065 -0.3048)
			(stroke
				(width 0.1)
				(type default)
			)
			(layer "B.Fab")
		)
		(fp_line
			(start -0.12065 -0.3048)
			(end -0.67945 -0.3048)
			(stroke
				(width 0.1)
				(type default)
			)
			(layer "B.Fab")
		)
		(fp_line
			(start -0.67945 0.3048)
			(end -0.120396 0.3048)
			(stroke
				(width 0.1)
				(type default)
			)
			(layer "B.Fab")
		)
		(fp_line
			(start -0.67945 -0.3048)
			(end -0.67945 0.3048)
			(stroke
				(width 0.1)
				(type default)
			)
			(layer "B.Fab")
		)
		(pad "1" smd circle
			(at 0.40005 0)
			(size 0 0)
			(layers "B.Cu" "B.Mask" "B.Paste")
			(net "FM_PVDDCR_CPU1_P1_EN")
		)
		(pad "2" smd circle
			(at -0.40005 0)
			(size 0 0)
			(layers "B.Cu" "B.Mask" "B.Paste")
			(net "PVDDCR_CPU1_P1_EN_R")
		)
	)
	(footprint ""
		(layer "B.Cu")
		(at 53.278024 -408.517344 90)
		(property "Reference" "C6663"
			(at 0 0 90)
			(layer "B.SilkS")
			(hide yes)
			(effects
				(font
					(size 1.27 1.27)
				)
				(justify mirror)
			)
		)
		(property "Value" ""
			(at 0 0 90)
			(layer "B.Fab")
			(effects
				(font
					(size 1.27 1.27)
				)
				(justify mirror)
			)
		)
		(duplicate_pad_numbers_are_jumpers no)
		(fp_line
			(start 0.299974 -0.150114)
			(end -0.299974 -0.150114)
			(stroke
				(width 0.1)
				(type default)
			)
			(layer "B.Fab")
		)
		(fp_line
			(start -0.299974 -0.150114)
			(end -0.299974 0.150114)
			(stroke
				(width 0.1)
				(type default)
			)
			(layer "B.Fab")
		)
		(fp_line
			(start 0.299974 0.150114)
			(end 0.299974 -0.150114)
			(stroke
				(width 0.1)
				(type default)
			)
			(layer "B.Fab")
		)
		(fp_line
			(start -0.299974 0.150114)
			(end 0.299974 0.150114)
			(stroke
				(width 0.1)
				(type default)
			)
			(layer "B.Fab")
		)
		(pad "1" smd rect
			(at 0.2667 0 270)
			(size 0.3048 0.381)
			(layers "B.Cu" "B.Mask" "B.Paste")
			(net "P5E_CPU1_P1_TX_BUF_C_DP<1>")
		)
		(pad "2" smd rect
			(at -0.2667 0 270)
			(size 0.3048 0.381)
			(layers "B.Cu" "B.Mask" "B.Paste")
			(net "P5E_CPU1_P1_TX_BUF_DP<1>")
		)
	)
	(footprint ""
		(layer "B.Cu")
		(at 305.423316 -427.2788 180)
		(property "Reference" "R1438"
			(at 0 0 0)
			(layer "B.SilkS")
			(hide yes)
			(effects
				(font
					(size 1.27 1.27)
				)
				(justify mirror)
			)
		)
		(property "Value" ""
			(at 0 0 0)
			(layer "B.Fab")
			(effects
				(font
					(size 1.27 1.27)
				)
				(justify mirror)
			)
		)
		(duplicate_pad_numbers_are_jumpers no)
		(fp_line
			(start 0.32512 0.175006)
			(end 0.32512 -0.175006)
			(stroke
				(width 0.1)
				(type default)
			)
			(layer "B.Fab")
		)
		(fp_line
			(start 0.32512 -0.175006)
			(end -0.32512 -0.175006)
			(stroke
				(width 0.1)
				(type default)
			)
			(layer "B.Fab")
		)
		(fp_line
			(start -0.32512 0.175006)
			(end 0.32512 0.175006)
			(stroke
				(width 0.1)
				(type default)
			)
			(layer "B.Fab")
		)
		(fp_line
			(start -0.32512 -0.175006)
			(end -0.32512 0.175006)
			(stroke
				(width 0.1)
				(type default)
			)
			(layer "B.Fab")
		)
		(pad "1" smd rect
			(at 0.2667 0)
			(size 0.3048 0.381)
			(layers "B.Cu" "B.Mask" "B.Paste")
			(net "P1V8_CPU0_RT_1D")
		)
		(pad "2" smd rect
			(at -0.2667 0 180)
			(size 0.3048 0.381)
			(layers "B.Cu" "B.Mask" "B.Paste")
			(net "JTAG_TDI_RT_CPU0_P0")
		)
	)
)
